# T6G (Grand Teton) — schematic netlist excerpt (pin names and nets, part order shuffled) for the footprints in the layout excerpt that follows; sources: Cadence DE-HDL packaged netlist, KiCad conversion of 04192023_DAF0TMB3IC0_F0TG_MB_C_brd_V02_OCP.brd

R4558  Q_RES  33.2 1% CHIP  pkg 0402LF  page 81 : A = SWB_HSC_EN_R ; B = SWB_HSC_EN
PC562_3  Q_CAP  22UF 4V 20% X6S  pkg C0805  page 195 : A = PVDDCR_CPU0_P0 ; B = GND
R8566  Q_RES  0 5% CHIP  pkg 0402LF  page 28 : A = CLK_100M_CPU0_CLK03_R_DN ; B = CLK_100M_CPU0_CLK03_DN

(kicad_pcb
	(version 20260206)
	(generator "pcbnew")
	(generator_version "10.0")
	(general
		(thickness 1.6)
		(legacy_teardrops no)
	)
	(paper "A4")
	(title_block
		(title "04192023_DAF0TMB3IC0_F0TG_MB_C_brd_V02_OCP.brd")
		(comment 1 "Grand Teton / footprints 7103-7105 of 8354")
	)
	(layers
		(0 "F.Cu" signal "TOP")
		(4 "In1.Cu" signal "GND")
		(6 "In2.Cu" signal "IN1")
		(8 "In3.Cu" signal "GND1")
		(10 "In4.Cu" signal "IN2")
		(12 "In5.Cu" signal "GND2")
		(14 "In6.Cu" signal "IN3")
		(16 "In7.Cu" signal "GND3")
		(18 "In8.Cu" signal "VCC")
		(20 "In9.Cu" signal "VCC1")
		(22 "In10.Cu" signal "GND4")
		(24 "In11.Cu" signal "IN4")
		(26 "In12.Cu" signal "GND5")
		(28 "In13.Cu" signal "IN5")
		(30 "In14.Cu" signal "GND6")
		(32 "In15.Cu" signal "IN6")
		(34 "In16.Cu" signal "GND7")
		(2 "B.Cu" signal "BOTTOM")
		(9 "F.Adhes" user "F.Adhesive")
		(11 "B.Adhes" user "B.Adhesive")
		(13 "F.Paste" user "Package Geometry/Pastemask Top")
		(15 "B.Paste" user "Package Geometry/Pastemask Bottom")
		(5 "F.SilkS" user "Ref Des/Silkscreen Top")
		(7 "B.SilkS" user "Ref Des/Silkscreen Bottom")
		(1 "F.Mask" user "Board Geometry/Soldermask Top")
		(3 "B.Mask" user "Board Geometry/Soldermask Bottom")
		(17 "Dwgs.User" user "User.Drawings")
		(19 "Cmts.User" user "User.Comments")
		(21 "Eco1.User" user "User.Eco1")
		(23 "Eco2.User" user "User.Eco2")
		(25 "Edge.Cuts" user "Board Geometry/Outline")
		(27 "Margin" user)
		(31 "F.CrtYd" user "Package Geometry/Place Bound Top")
		(29 "B.CrtYd" user "Package Geometry/Place Bound Bottom")
		(35 "F.Fab" user "Ref Des/Assembly Top")
		(33 "B.Fab" user "Ref Des/Assembly Bottom")
	)
	(footprint ""
		(layer "B.Cu")
		(at 375.604786 -214.523828 90)
		(property "Reference" "R8566"
			(at 0 0 90)
			(layer "B.SilkS")
			(hide yes)
			(effects
				(font
					(size 1.27 1.27)
				)
				(justify mirror)
			)
		)
		(property "Value" ""
			(at 0 0 90)
			(layer "B.Fab")
			(effects
				(font
					(size 1.27 1.27)
				)
				(justify mirror)
			)
		)
		(duplicate_pad_numbers_are_jumpers no)
		(fp_line
			(start 0.7874 -0.4064)
			(end -0.7874 -0.4064)
			(stroke
				(width 0.1524)
				(type default)
			)
			(layer "B.SilkS")
		)
		(fp_line
			(start -0.7874 -0.4064)
			(end -0.7874 0.010414)
			(stroke
				(width 0.1524)
				(type default)
			)
			(layer "B.SilkS")
		)
		(fp_line
			(start 0.7874 -0.014986)
			(end 0.7874 -0.4064)
			(stroke
				(width 0.1524)
				(type default)
			)
			(layer "B.SilkS")
		)
		(fp_line
			(start -0.351028 0.4064)
			(end 0.385572 0.4064)
			(stroke
				(width 0.1524)
				(type default)
			)
			(layer "B.SilkS")
		)
		(fp_line
			(start 0.67945 -0.305054)
			(end 0.12065 -0.305054)
			(stroke
				(width 0.1)
				(type default)
			)
			(layer "B.Fab")
		)
		(fp_line
			(start 0.12065 -0.305054)
			(end 0.12065 -0.2794)
			(stroke
				(width 0.1)
				(type default)
			)
			(layer "B.Fab")
		)
		(fp_line
			(start -0.12065 -0.3048)
			(end -0.67945 -0.3048)
			(stroke
				(width 0.1)
				(type default)
			)
			(layer "B.Fab")
		)
		(fp_line
			(start -0.67945 -0.3048)
			(end -0.67945 0.3048)
			(stroke
				(width 0.1)
				(type default)
			)
			(layer "B.Fab")
		)
		(fp_line
			(start 0.12065 -0.2794)
			(end -0.12065 -0.2794)
			(stroke
				(width 0.1)
				(type default)
			)
			(layer "B.Fab")
		)
		(fp_line
			(start -0.12065 -0.2794)
			(end -0.12065 -0.3048)
			(stroke
				(width 0.1)
				(type default)
			)
			(layer "B.Fab")
		)
		(fp_line
			(start 0.12065 0.2794)
			(end 0.12065 0.3048)
			(stroke
				(width 0.1)
				(type default)
			)
			(layer "B.Fab")
		)
		(fp_line
			(start -0.120396 0.2794)
			(end 0.12065 0.2794)
			(stroke
				(width 0.1)
				(type default)
			)
			(layer "B.Fab")
		)
		(fp_line
			(start 0.67945 0.3048)
			(end 0.67945 -0.305054)
			(stroke
				(width 0.1)
				(type default)
			)
			(layer "B.Fab")
		)
		(fp_line
			(start 0.12065 0.3048)
			(end 0.67945 0.3048)
			(stroke
				(width 0.1)
				(type default)
			)
			(layer "B.Fab")
		)
		(fp_line
			(start -0.120396 0.3048)
			(end -0.120396 0.2794)
			(stroke
				(width 0.1)
				(type default)
			)
			(layer "B.Fab")
		)
		(fp_line
			(start -0.67945 0.3048)
			(end -0.120396 0.3048)
			(stroke
				(width 0.1)
				(type default)
			)
			(layer "B.Fab")
		)
		(pad "1" smd circle
			(at 0.40005 0 270)
			(size 0 0)
			(layers "B.Cu" "B.Mask" "B.Paste")
			(net "CLK_100M_CPU0_CLK03_R_DN")
		)
		(pad "2" smd circle
			(at -0.40005 0 270)
			(size 0 0)
			(layers "B.Cu" "B.Mask" "B.Paste")
			(net "CLK_100M_CPU0_CLK03_DN")
		)
	)
	(footprint ""
		(layer "B.Cu")
		(at 197.269608 -119.721376 180)
		(property "Reference" "R4558"
			(at 0 0 0)
			(layer "B.SilkS")
			(hide yes)
			(effects
				(font
					(size 1.27 1.27)
				)
				(justify mirror)
			)
		)
		(property "Value" ""
			(at 0 0 0)
			(layer "B.Fab")
			(effects
				(font
					(size 1.27 1.27)
				)
				(justify mirror)
			)
		)
		(duplicate_pad_numbers_are_jumpers no)
		(fp_line
			(start 0.7874 0.4064)
			(end 0.7874 -0.4064)
			(stroke
				(width 0.1524)
				(type default)
			)
			(layer "B.SilkS")
		)
		(fp_line
			(start 0.7874 -0.4064)
			(end -0.7874 -0.4064)
			(stroke
				(width 0.1524)
				(type default)
			)
			(layer "B.SilkS")
		)
		(fp_line
			(start -0.7874 0.4064)
			(end 0.7874 0.4064)
			(stroke
				(width 0.1524)
				(type default)
			)
			(layer "B.SilkS")
		)
		(fp_line
			(start -0.7874 -0.4064)
			(end -0.7874 0.4064)
			(stroke
				(width 0.1524)
				(type default)
			)
			(layer "B.SilkS")
		)
		(fp_line
			(start 0.67945 0.3048)
			(end 0.67945 -0.305054)
			(stroke
				(width 0.1)
				(type default)
			)
			(layer "B.Fab")
		)
		(fp_line
			(start 0.67945 -0.305054)
			(end 0.12065 -0.305054)
			(stroke
				(width 0.1)
				(type default)
			)
			(layer "B.Fab")
		)
		(fp_line
			(start 0.12065 0.3048)
			(end 0.67945 0.3048)
			(stroke
				(width 0.1)
				(type default)
			)
			(layer "B.Fab")
		)
		(fp_line
			(start 0.12065 0.2794)
			(end 0.12065 0.3048)
			(stroke
				(width 0.1)
				(type default)
			)
			(layer "B.Fab")
		)
		(fp_line
			(start 0.12065 -0.2794)
			(end -0.12065 -0.2794)
			(stroke
				(width 0.1)
				(type default)
			)
			(layer "B.Fab")
		)
		(fp_line
			(start 0.12065 -0.305054)
			(end 0.12065 -0.2794)
			(stroke
				(width 0.1)
				(type default)
			)
			(layer "B.Fab")
		)
		(fp_line
			(start -0.120396 0.3048)
			(end -0.120396 0.2794)
			(stroke
				(width 0.1)
				(type default)
			)
			(layer "B.Fab")
		)
		(fp_line
			(start -0.120396 0.2794)
			(end 0.12065 0.2794)
			(stroke
				(width 0.1)
				(type default)
			)
			(layer "B.Fab")
		)
		(fp_line
			(start -0.12065 -0.2794)
			(end -0.12065 -0.3048)
			(stroke
				(width 0.1)
				(type default)
			)
			(layer "B.Fab")
		)
		(fp_line
			(start -0.12065 -0.3048)
			(end -0.67945 -0.3048)
			(stroke
				(width 0.1)
				(type default)
			)
			(layer "B.Fab")
		)
		(fp_line
			(start -0.67945 0.3048)
			(end -0.120396 0.3048)
			(stroke
				(width 0.1)
				(type default)
			)
			(layer "B.Fab")
		)
		(fp_line
			(start -0.67945 -0.3048)
			(end -0.67945 0.3048)
			(stroke
				(width 0.1)
				(type default)
			)
			(layer "B.Fab")
		)
		(pad "1" smd circle
			(at 0.40005 0)
			(size 0 0)
			(layers "B.Cu" "B.Mask" "B.Paste")
			(net "SWB_HSC_EN_R")
		)
		(pad "2" smd circle
			(at -0.40005 0)
			(size 0 0)
			(layers "B.Cu" "B.Mask" "B.Paste")
			(net "SWB_HSC_EN")
		)
	)
	(footprint ""
		(layer "B.Cu")
		(at 383.655316 -191.334898 90)
		(property "Reference" "PC562_3"
			(at 0 0 90)
			(layer "B.SilkS")
			(hide yes)
			(effects
				(font
					(size 1.27 1.27)
				)
				(justify mirror)
			)
		)
		(property "Value" ""
			(at 0 0 90)
			(layer "B.Fab")
			(effects
				(font
					(size 1.27 1.27)
				)
				(justify mirror)
			)
		)
		(duplicate_pad_numbers_are_jumpers no)
		(fp_line
			(start 1.524 -0.762)
			(end -1.524 -0.762)
			(stroke
				(width 0.1524)
				(type default)
			)
			(layer "B.SilkS")
		)
		(fp_line
			(start -1.524 -0.762)
			(end -1.524 0.762)
			(stroke
				(width 0.1524)
				(type default)
			)
			(layer "B.SilkS")
		)
		(fp_line
			(start 1.524 0.762)
			(end 1.524 -0.762)
			(stroke
				(width 0.1524)
				(type default)
			)
			(layer "B.SilkS")
		)
		(fp_line
			(start -1.524 0.762)
			(end 1.524 0.762)
			(stroke
				(width 0.1524)
				(type default)
			)
			(layer "B.SilkS")
		)
		(fp_line
			(start 1.1049 -0.724916)
			(end 1.1049 0.724916)
			(stroke
				(width 0.1)
				(type default)
			)
			(layer "B.Fab")
		)
		(fp_line
			(start -1.1049 -0.724916)
			(end 1.1049 -0.724916)
			(stroke
				(width 0.1)
				(type default)
			)
			(layer "B.Fab")
		)
		(fp_line
			(start 1.1049 0.724916)
			(end -1.1049 0.724916)
			(stroke
				(width 0.1)
				(type default)
			)
			(layer "B.Fab")
		)
		(fp_line
			(start -1.1049 0.724916)
			(end -1.1049 -0.724916)
			(stroke
				(width 0.1)
				(type default)
			)
			(layer "B.Fab")
		)
		(pad "1" smd rect
			(at 0.889 0 90)
			(size 1.016 1.27)
			(layers "B.Cu" "B.Mask" "B.Paste")
			(net "PVDDCR_CPU0_P0")
		)
		(pad "2" smd rect
			(at -0.889 0 90)
			(size 1.016 1.27)
			(layers "B.Cu" "B.Mask" "B.Paste")
			(net "GND")
		)
	)
)
